(kicad_pcb
	(version 20260206)
	(generator "pcbnew")
	(generator_version "10.0")
	(general
		(thickness 1.6)
		(legacy_teardrops no)
	)
	(paper "A4")
	(title_block
		(title "Bryce Canyon_SCC_16316-1_OCP.brd")
		(comment 1 "Bryce Canyon / footprints 497-503 of 1561")
	)
	(layers
		(0 "F.Cu" signal "TOP")
		(4 "In1.Cu" signal "L2GND")
		(6 "In2.Cu" signal "L3")
		(8 "In3.Cu" signal "L4VCC")
		(10 "In4.Cu" signal "L5VCC")
		(12 "In5.Cu" signal "L6")
		(14 "In6.Cu" signal "L7GND")
		(2 "B.Cu" signal "BOTTOM")
		(9 "F.Adhes" user "F.Adhesive")
		(11 "B.Adhes" user "B.Adhesive")
		(13 "F.Paste" user "Package Geometry/Pastemask Top")
		(15 "B.Paste" user "Package Geometry/Pastemask Bottom")
		(5 "F.SilkS" user "Ref Des/Silkscreen Top")
		(7 "B.SilkS" user "Ref Des/Silkscreen Bottom")
		(1 "F.Mask" user "Board Geometry/Soldermask Top")
		(3 "B.Mask" user "Board Geometry/Soldermask Bottom")
		(17 "Dwgs.User" user "User.Drawings")
		(19 "Cmts.User" user "User.Comments")
		(21 "Eco1.User" user "User.Eco1")
		(23 "Eco2.User" user "User.Eco2")
		(25 "Edge.Cuts" user "Board Geometry/Outline")
		(27 "Margin" user)
		(31 "F.CrtYd" user "Package Geometry/Place Bound Top")
		(29 "B.CrtYd" user "Package Geometry/Place Bound Bottom")
		(35 "F.Fab" user "Ref Des/Assembly Top")
		(33 "B.Fab" user "Ref Des/Assembly Bottom")
	)
	(footprint ""
		(layer "F.Cu")
		(at 21.79193 -94.850204 180)
		(property "Reference" "R416"
			(at 0 0 180)
			(layer "F.SilkS")
			(hide yes)
			(effects
				(font
					(size 1.27 1.27)
				)
			)
		)
		(property "Value" "200KR2F-L-GP"
			(at 0.064008 -3.993896 180)
			(unlocked yes)
			(layer "F.Fab")
			(hide yes)
			(effects
				(font
					(size 1.016 1.016)
					(thickness 0.1524)
				)
			)
		)
		(property "Device Type" "R402H16"
			(at 0.064008 -5.517896 180)
			(unlocked yes)
			(layer "F.Fab")
			(hide yes)
			(effects
				(font
					(size 1.016 1.016)
					(thickness 0.1524)
				)
			)
		)
		(duplicate_pad_numbers_are_jumpers no)
		(fp_line
			(start 0.508 -0.9398)
			(end -0.508 -0.9398)
			(stroke
				(width 0.1524)
				(type default)
			)
			(layer "F.SilkS")
		)
		(fp_line
			(start -0.508 -0.9398)
			(end -0.508 0.9398)
			(stroke
				(width 0.1524)
				(type default)
			)
			(layer "F.SilkS")
		)
		(fp_rect
			(start -0.508 0.9398)
			(end 0.508 -0.9398)
			(stroke
				(width 0)
				(type default)
			)
			(fill no)
			(layer "F.CrtYd")
		)
		(fp_rect
			(start -0.508 0.9398)
			(end 0.508 -0.9398)
			(stroke
				(width 0)
				(type default)
			)
			(fill no)
			(layer "F.Fab")
		)
		(pad "1" smd custom
			(at 0 -0.4445 180)
			(size 0.1397 0.1397)
			(layers "F.Cu" "F.Mask" "F.Paste")
			(net "LS_EN_U46")
			(options
				(clearance outline)
				(anchor circle)
			)
			(primitives
				(gr_poly
					(pts
						(arc
							(start -0.1778 -0.2794)
							(mid -0.249642 -0.249642)
							(end -0.2794 -0.1778)
						)
						(arc
							(start -0.2794 0.1778)
							(mid -0.249642 0.249642)
							(end -0.1778 0.2794)
						)
						(arc
							(start 0.1778 0.2794)
							(mid 0.249642 0.249642)
							(end 0.2794 0.1778)
						)
						(arc
							(start 0.2794 -0.1778)
							(mid 0.249642 -0.249642)
							(end 0.1778 -0.2794)
						)
					)
					(width 0)
					(fill yes)
				)
			)
		)
		(pad "2" smd custom
			(at 0 0.4445 180)
			(size 0.1397 0.1397)
			(layers "F.Cu" "F.Mask" "F.Paste")
			(net "P0V9_PG")
			(options
				(clearance outline)
				(anchor circle)
			)
			(primitives
				(gr_poly
					(pts
						(arc
							(start -0.1778 -0.2794)
							(mid -0.249642 -0.249642)
							(end -0.2794 -0.1778)
						)
						(arc
							(start -0.2794 0.1778)
							(mid -0.249642 0.249642)
							(end -0.1778 0.2794)
						)
						(arc
							(start 0.1778 0.2794)
							(mid 0.249642 0.249642)
							(end 0.2794 0.1778)
						)
						(arc
							(start 0.2794 -0.1778)
							(mid 0.249642 -0.249642)
							(end 0.1778 -0.2794)
						)
					)
					(width 0)
					(fill yes)
				)
			)
		)
	)
	(footprint ""
		(layer "F.Cu")
		(at 6.5786 -52.1462 180)
		(property "Reference" "R532"
			(at 0 0 180)
			(layer "F.SilkS")
			(hide yes)
			(effects
				(font
					(size 1.27 1.27)
				)
			)
		)
		(property "Value" "100KR2F-L1-GP"
			(at 0.064008 -3.993896 180)
			(unlocked yes)
			(layer "F.Fab")
			(hide yes)
			(effects
				(font
					(size 1.016 1.016)
					(thickness 0.1524)
				)
			)
		)
		(property "Device Type" "R402H16"
			(at 0.064008 -5.517896 180)
			(unlocked yes)
			(layer "F.Fab")
			(hide yes)
			(effects
				(font
					(size 1.016 1.016)
					(thickness 0.1524)
				)
			)
		)
		(duplicate_pad_numbers_are_jumpers no)
		(fp_line
			(start 0.508 -0.9398)
			(end -0.508 -0.9398)
			(stroke
				(width 0.1524)
				(type default)
			)
			(layer "F.SilkS")
		)
		(fp_line
			(start -0.508 -0.9398)
			(end -0.508 0.9398)
			(stroke
				(width 0.1524)
				(type default)
			)
			(layer "F.SilkS")
		)
		(fp_rect
			(start -0.508 0.9398)
			(end 0.508 -0.9398)
			(stroke
				(width 0)
				(type default)
			)
			(fill no)
			(layer "F.CrtYd")
		)
		(fp_rect
			(start -0.508 0.9398)
			(end 0.508 -0.9398)
			(stroke
				(width 0)
				(type default)
			)
			(fill no)
			(layer "F.Fab")
		)
		(pad "1" smd custom
			(at 0 -0.4445 180)
			(size 0.1397 0.1397)
			(layers "F.Cu" "F.Mask" "F.Paste")
			(net "P12V_STBY_SCC")
			(options
				(clearance outline)
				(anchor circle)
			)
			(primitives
				(gr_poly
					(pts
						(arc
							(start -0.1778 -0.2794)
							(mid -0.249642 -0.249642)
							(end -0.2794 -0.1778)
						)
						(arc
							(start -0.2794 0.1778)
							(mid -0.249642 0.249642)
							(end -0.1778 0.2794)
						)
						(arc
							(start 0.1778 0.2794)
							(mid 0.249642 0.249642)
							(end 0.2794 0.1778)
						)
						(arc
							(start 0.2794 -0.1778)
							(mid 0.249642 -0.249642)
							(end 0.1778 -0.2794)
						)
					)
					(width 0)
					(fill yes)
				)
			)
		)
		(pad "2" smd custom
			(at 0 0.4445 180)
			(size 0.1397 0.1397)
			(layers "F.Cu" "F.Mask" "F.Paste")
			(net "MB0_P12V_PWGIN_R")
			(options
				(clearance outline)
				(anchor circle)
			)
			(primitives
				(gr_poly
					(pts
						(arc
							(start -0.1778 -0.2794)
							(mid -0.249642 -0.249642)
							(end -0.2794 -0.1778)
						)
						(arc
							(start -0.2794 0.1778)
							(mid -0.249642 0.249642)
							(end -0.1778 0.2794)
						)
						(arc
							(start 0.1778 0.2794)
							(mid 0.249642 0.249642)
							(end 0.2794 0.1778)
						)
						(arc
							(start 0.2794 -0.1778)
							(mid 0.249642 -0.249642)
							(end 0.1778 -0.2794)
						)
					)
					(width 0)
					(fill yes)
				)
			)
		)
	)
	(footprint ""
		(layer "F.Cu")
		(at 200.49998 -131.430014)
		(property "Reference" "RHOLE1"
			(at 0 0 0)
			(layer "F.SilkS")
			(hide yes)
			(effects
				(font
					(size 1.27 1.27)
				)
			)
		)
		(property "Value" "HOLE709R146-3P-S2-GP"
			(at -10.312908 -1.750314 0)
			(unlocked yes)
			(layer "F.Fab")
			(hide yes)
			(effects
				(font
					(size 1.016 1.016)
					(thickness 0.1524)
				)
			)
		)
		(property "Device Type" "HOLE709R146-3P-S2"
			(at -10.312908 -3.274314 0)
			(unlocked yes)
			(layer "F.Fab")
			(hide yes)
			(effects
				(font
					(size 1.016 1.016)
					(thickness 0.1524)
				)
			)
		)
		(duplicate_pad_numbers_are_jumpers no)
		(fp_poly
			(pts
				(arc
					(start 4.8006 -7.975854)
					(mid -9.309136 0)
					(end 4.8006 7.975854)
				)
			)
			(stroke
				(width 0)
				(type default)
			)
			(fill no)
			(layer "B.CrtYd")
		)
		(fp_poly
			(pts
				(arc
					(start 4.8006 -7.975854)
					(mid -9.309136 0)
					(end 4.8006 7.975854)
				)
			)
			(stroke
				(width 0)
				(type default)
			)
			(fill no)
			(layer "F.CrtYd")
		)
		(fp_poly
			(pts
				(arc
					(start 4.8006 -7.975854)
					(mid -9.309136 0)
					(end 4.8006 7.975854)
				)
			)
			(stroke
				(width 0)
				(type default)
			)
			(fill no)
			(layer "B.Fab")
		)
		(fp_poly
			(pts
				(arc
					(start 4.8006 -7.975854)
					(mid -9.309136 0)
					(end 4.8006 7.975854)
				)
			)
			(stroke
				(width 0)
				(type default)
			)
			(fill no)
			(layer "F.Fab")
		)
		(pad "1" thru_hole circle
			(at 0 -4.500118)
			(size 2.5146 2.5146)
			(drill 2.1082)
			(layers "*.Cu" "*.Mask")
			(remove_unused_layers no)
			(net "GND")
			(clearance 0.1524)
			(thermal_gap 0.1524)
		)
		(pad "2" thru_hole custom
			(at 0 0)
			(size 3.374898 3.374898)
			(drill 3.7084)
			(layers "*.Cu" "*.Mask")
			(remove_unused_layers no)
			(net "GND")
			(clearance -4.38785)
			(thermal_gap 0.3048)
			(options
				(clearance outline)
				(anchor circle)
			)
			(primitives
				(gr_poly
					(pts
						(arc
							(start 6.75005 -7.80161)
							(mid -6.750045 0)
							(end 6.75005 7.80161)
						)
					)
					(width 0)
					(fill yes)
				)
			)
			(padstack
				(mode front_inner_back)
				(layer "Inner"
					(shape circle)
					(size 4.1148 4.1148)
					(clearance 0.3048)
				)
				(layer "B.Cu"
					(shape custom)
					(size 3.374898 3.374898)
					(options
						(anchor circle)
					)
					(primitives
						(gr_poly
							(pts
								(arc
									(start 6.75005 -7.80161)
									(mid -6.750045 0)
									(end 6.75005 7.80161)
								)
							)
							(width 0)
							(fill yes)
						)
					)
					(clearance -4.38785)
				)
			)
		)
		(pad "3" thru_hole circle
			(at 0 4.500118)
			(size 1.9812 1.9812)
			(drill 1.5748)
			(layers "*.Cu" "*.Mask")
			(remove_unused_layers no)
			(net "GND")
			(clearance 0.1524)
			(thermal_gap 0.1524)
		)
	)
	(footprint ""
		(layer "F.Cu")
		(at 23.79853 -94.850204 180)
		(property "Reference" "R449"
			(at 0 0 180)
			(layer "F.SilkS")
			(hide yes)
			(effects
				(font
					(size 1.27 1.27)
				)
			)
		)
		(property "Value" "200KR2F-L-GP"
			(at 0.064008 -3.993896 180)
			(unlocked yes)
			(layer "F.Fab")
			(hide yes)
			(effects
				(font
					(size 1.016 1.016)
					(thickness 0.1524)
				)
			)
		)
		(property "Device Type" "R402H16"
			(at 0.064008 -5.517896 180)
			(unlocked yes)
			(layer "F.Fab")
			(hide yes)
			(effects
				(font
					(size 1.016 1.016)
					(thickness 0.1524)
				)
			)
		)
		(duplicate_pad_numbers_are_jumpers no)
		(fp_line
			(start 0.508 -0.9398)
			(end -0.508 -0.9398)
			(stroke
				(width 0.1524)
				(type default)
			)
			(layer "F.SilkS")
		)
		(fp_line
			(start -0.508 -0.9398)
			(end -0.508 0.9398)
			(stroke
				(width 0.1524)
				(type default)
			)
			(layer "F.SilkS")
		)
		(fp_rect
			(start -0.508 0.9398)
			(end 0.508 -0.9398)
			(stroke
				(width 0)
				(type default)
			)
			(fill no)
			(layer "F.CrtYd")
		)
		(fp_rect
			(start -0.508 0.9398)
			(end 0.508 -0.9398)
			(stroke
				(width 0)
				(type default)
			)
			(fill no)
			(layer "F.Fab")
		)
		(pad "1" smd custom
			(at 0 -0.4445 180)
			(size 0.1397 0.1397)
			(layers "F.Cu" "F.Mask" "F.Paste")
			(net "VREF1")
			(options
				(clearance outline)
				(anchor circle)
			)
			(primitives
				(gr_poly
					(pts
						(arc
							(start -0.1778 -0.2794)
							(mid -0.249642 -0.249642)
							(end -0.2794 -0.1778)
						)
						(arc
							(start -0.2794 0.1778)
							(mid -0.249642 0.249642)
							(end -0.1778 0.2794)
						)
						(arc
							(start 0.1778 0.2794)
							(mid 0.249642 0.249642)
							(end 0.2794 0.1778)
						)
						(arc
							(start 0.2794 -0.1778)
							(mid 0.249642 -0.249642)
							(end 0.1778 -0.2794)
						)
					)
					(width 0)
					(fill yes)
				)
			)
		)
		(pad "2" smd custom
			(at 0 0.4445 180)
			(size 0.1397 0.1397)
			(layers "F.Cu" "F.Mask" "F.Paste")
			(net "P3V3")
			(options
				(clearance outline)
				(anchor circle)
			)
			(primitives
				(gr_poly
					(pts
						(arc
							(start -0.1778 -0.2794)
							(mid -0.249642 -0.249642)
							(end -0.2794 -0.1778)
						)
						(arc
							(start -0.2794 0.1778)
							(mid -0.249642 0.249642)
							(end -0.1778 0.2794)
						)
						(arc
							(start 0.1778 0.2794)
							(mid 0.249642 0.249642)
							(end 0.2794 0.1778)
						)
						(arc
							(start 0.2794 -0.1778)
							(mid 0.249642 -0.249642)
							(end 0.1778 -0.2794)
						)
					)
					(width 0)
					(fill yes)
				)
			)
		)
	)
	(footprint ""
		(layer "F.Cu")
		(at 71.172324 -75.548236 90)
		(property "Reference" "R541"
			(at 0 0 90)
			(layer "F.SilkS")
			(hide yes)
			(effects
				(font
					(size 1.27 1.27)
				)
			)
		)
		(property "Value" "0R2J-2-GP"
			(at 0.064008 -3.993896 90)
			(unlocked yes)
			(layer "F.Fab")
			(hide yes)
			(effects
				(font
					(size 1.016 1.016)
					(thickness 0.1524)
				)
			)
		)
		(property "Device Type" "R402H16"
			(at 0.064008 -5.517896 90)
			(unlocked yes)
			(layer "F.Fab")
			(hide yes)
			(effects
				(font
					(size 1.016 1.016)
					(thickness 0.1524)
				)
			)
		)
		(duplicate_pad_numbers_are_jumpers no)
		(fp_line
			(start 0.508 -0.9398)
			(end -0.508 -0.9398)
			(stroke
				(width 0.1524)
				(type default)
			)
			(layer "F.SilkS")
		)
		(fp_line
			(start -0.508 -0.9398)
			(end -0.508 0.9398)
			(stroke
				(width 0.1524)
				(type default)
			)
			(layer "F.SilkS")
		)
		(fp_rect
			(start -0.508 0.9398)
			(end 0.508 -0.9398)
			(stroke
				(width 0)
				(type default)
			)
			(fill no)
			(layer "F.CrtYd")
		)
		(fp_rect
			(start -0.508 0.9398)
			(end 0.508 -0.9398)
			(stroke
				(width 0)
				(type default)
			)
			(fill no)
			(layer "F.Fab")
		)
		(pad "1" smd custom
			(at 0 -0.4445 90)
			(size 0.1397 0.1397)
			(layers "F.Cu" "F.Mask" "F.Paste")
			(net "I2C_EXP_IOC_SDA8")
			(options
				(clearance outline)
				(anchor circle)
			)
			(primitives
				(gr_poly
					(pts
						(arc
							(start -0.1778 -0.2794)
							(mid -0.249642 -0.249642)
							(end -0.2794 -0.1778)
						)
						(arc
							(start -0.2794 0.1778)
							(mid -0.249642 0.249642)
							(end -0.1778 0.2794)
						)
						(arc
							(start 0.1778 0.2794)
							(mid 0.249642 0.249642)
							(end 0.2794 0.1778)
						)
						(arc
							(start 0.2794 -0.1778)
							(mid 0.249642 -0.249642)
							(end 0.1778 -0.2794)
						)
					)
					(width 0)
					(fill yes)
				)
			)
		)
		(pad "2" smd custom
			(at 0 0.4445 90)
			(size 0.1397 0.1397)
			(layers "F.Cu" "F.Mask" "F.Paste")
			(net "I2C_IOC_4_R_SDA")
			(options
				(clearance outline)
				(anchor circle)
			)
			(primitives
				(gr_poly
					(pts
						(arc
							(start -0.1778 -0.2794)
							(mid -0.249642 -0.249642)
							(end -0.2794 -0.1778)
						)
						(arc
							(start -0.2794 0.1778)
							(mid -0.249642 0.249642)
							(end -0.1778 0.2794)
						)
						(arc
							(start 0.1778 0.2794)
							(mid 0.249642 0.249642)
							(end 0.2794 0.1778)
						)
						(arc
							(start 0.2794 -0.1778)
							(mid 0.249642 -0.249642)
							(end 0.1778 -0.2794)
						)
					)
					(width 0)
					(fill yes)
				)
			)
		)
	)
	(footprint ""
		(layer "F.Cu")
		(at 142.673324 -104.872028 180)
		(property "Reference" "R26"
			(at 0 0 180)
			(layer "F.SilkS")
			(hide yes)
			(effects
				(font
					(size 1.27 1.27)
				)
			)
		)
		(property "Value" "0R5J-5-GP"
			(at 0 -8.9535 180)
			(unlocked yes)
			(layer "F.Fab")
			(hide yes)
			(effects
				(font
					(size 1.27 1.016)
					(thickness 0.1524)
				)
			)
		)
		(property "Device Type" "R805H24"
			(at 0 -10.6299 180)
			(unlocked yes)
			(layer "F.Fab")
			(hide yes)
			(effects
				(font
					(size 1.27 1.016)
					(thickness 0.1524)
				)
			)
		)
		(duplicate_pad_numbers_are_jumpers no)
		(fp_line
			(start 0.889 1.7018)
			(end 0.889 -0.508)
			(stroke
				(width 0.1524)
				(type default)
			)
			(layer "F.SilkS")
		)
		(fp_line
			(start 0.889 -1.7018)
			(end 0.889 -0.381)
			(stroke
				(width 0.1524)
				(type default)
			)
			(layer "F.SilkS")
		)
		(fp_line
			(start 0.889 -1.7018)
			(end -0.889 -1.7018)
			(stroke
				(width 0.1524)
				(type default)
			)
			(layer "F.SilkS")
		)
		(fp_line
			(start -0.889 1.7018)
			(end 0.889 1.7018)
			(stroke
				(width 0.1524)
				(type default)
			)
			(layer "F.SilkS")
		)
		(fp_line
			(start -0.889 0.0762)
			(end -0.889 1.7018)
			(stroke
				(width 0.1524)
				(type default)
			)
			(layer "F.SilkS")
		)
		(fp_line
			(start -0.889 -1.7018)
			(end -0.889 0.2794)
			(stroke
				(width 0.1524)
				(type default)
			)
			(layer "F.SilkS")
		)
		(fp_poly
			(pts
				(xy 0.9652 -1.778) (xy 0.9652 1.778) (xy -0.9652 1.778) (xy -0.9652 -1.778)
			)
			(stroke
				(width 0)
				(type default)
			)
			(fill no)
			(layer "F.CrtYd")
		)
		(fp_rect
			(start -0.9652 1.778)
			(end 0.9652 -1.778)
			(stroke
				(width 0)
				(type default)
			)
			(fill no)
			(layer "F.Fab")
		)
		(pad "1" smd rect
			(at 0 -0.9652 180)
			(size 1.397 1.143)
			(layers "F.Cu" "F.Mask" "F.Paste")
			(net "P1V5_E")
		)
		(pad "2" smd rect
			(at 0 0.9652 180)
			(size 1.397 1.143)
			(layers "F.Cu" "F.Mask" "F.Paste")
			(net "P1V5_E_OUT")
		)
	)
	(footprint ""
		(layer "F.Cu")
		(at 74.99985 -134.999984)
		(property "Reference" ""
			(at 0 0 0)
			(layer "F.SilkS")
			(hide yes)
			(effects
				(font
					(size 1.27 1.27)
				)
			)
		)
		(property "Value" "*"
			(at -6.38175 0.19685 0)
			(unlocked yes)
			(layer "F.Fab")
			(hide yes)
			(effects
				(font
					(size 1.016 1.016)
					(thickness 0.1524)
				)
			)
		)
		(duplicate_pad_numbers_are_jumpers no)
		(fp_poly
			(pts
				(arc
					(start 5.0673 0)
					(mid -5.0673 0)
					(end 5.0673 0)
				)
			)
			(stroke
				(width 0)
				(type default)
			)
			(fill no)
			(layer "B.CrtYd")
		)
		(fp_poly
			(pts
				(arc
					(start 5.0673 0)
					(mid -5.0673 0)
					(end 5.0673 0)
				)
			)
			(stroke
				(width 0)
				(type default)
			)
			(fill no)
			(layer "F.CrtYd")
		)
		(fp_poly
			(pts
				(arc
					(start 5.0673 0)
					(mid -5.0673 0)
					(end 5.0673 0)
				)
			)
			(stroke
				(width 0)
				(type default)
			)
			(fill no)
			(layer "B.Fab")
		)
		(fp_poly
			(pts
				(arc
					(start 5.0673 0)
					(mid -5.0673 0)
					(end 5.0673 0)
				)
			)
			(stroke
				(width 0)
				(type default)
			)
			(fill no)
			(layer "F.Fab")
		)
		(pad "1" thru_hole circle
			(at 0 0)
			(size 9.525 9.525)
			(drill 3.5052)
			(layers "*.Cu" "*.Mask")
			(remove_unused_layers no)
			(net "Net_7")
			(clearance -2.5019)
			(thermal_gap 0.3048)
			(padstack
				(mode front_inner_back)
				(layer "Inner"
					(shape circle)
					(size 3.9116 3.9116)
					(clearance 0.3048)
				)
				(layer "B.Cu"
					(shape circle)
					(size 9.525 9.525)
					(clearance -2.5019)
				)
			)
		)
	)
)
